FILE_TYPE = MULTI_PHYS_TABLE;
PART 'ADM809'
{========================================================================================}
:PACK_TYPE|MATERIAL|PART_NUMBER= EnvComp |PART_NUMBER|JEDEC_TYPE|CLASS|DESCRIPTION|HEIGHT|COMPONENT_TYPE|LEAD_LENGTH|LPID  | SPEED_URL | Status |RPL| AML | Bus_Unit | Days ;
{========================================================================================}
'SMLF'    | 'IC'     | 'D23047-001'(!) = 'YES;YES;UNK;UNK;ok;VLD' | 'D23047-001' | 'SOT23B'   | 'IC'  | '3.3V RESET W/PUSH PULL ADM809S' | '0.044 IN' | 'SMALLSMT'    | ''          | '801' | 'http://speed.intel.com:8081/speed/module/pdm/item/pdm_item_detail_direct.asp?item_cde=D23047-001&item_rev=01&url_param=unused' | 'Conditional' | 'YES' | '2' | 'SMO_IC' | '84' 
'SMLF'    | 'EMPTY'  | 'D23047-001'(!) = 'YES;YES;UNK;UNK;ok;VLD' | 'D23047-001' | 'SOT23B'   | 'IO'  | '3.3V RESET W/PUSH PULL ADM809S' | '0.044 IN' | 'SMALLSMT'    | ''          | '801' | 'http://speed.intel.com:8081/speed/module/pdm/item/pdm_item_detail_direct.asp?item_cde=D23047-001&item_rev=01&url_param=unused' | 'Conditional' | 'YES' | '2' | 'SMO_IC' | '84' 
END_PART
END.
